(kicad_pcb
	(version 20221018)
	(generator pcbnew)
	(general
    (thickness 1.7403)
  )
	(paper "A4")
	(title_block
    (title "Data Center RDIMM DDR4 Tester")
    (date "2024-09-30")
    (rev "1.2.4")
		(comment 9 "footprints 572-580 of 690")
	)
	(layers
    (0 "F.Cu" signal)
    (1 "In1.Cu" power)
    (2 "In2.Cu" signal)
    (3 "In3.Cu" power)
    (4 "In4.Cu" power)
    (5 "In5.Cu" signal)
    (6 "In6.Cu" power)
    (7 "In7.Cu" signal)
    (8 "In8.Cu" power)
    (9 "In9.Cu" signal)
    (10 "In10.Cu" power)
    (31 "B.Cu" signal)
    (32 "B.Adhes" user "B.Adhesive")
    (33 "F.Adhes" user "F.Adhesive")
    (34 "B.Paste" user)
    (35 "F.Paste" user)
    (36 "B.SilkS" user "B.Silkscreen")
    (37 "F.SilkS" user "F.Silkscreen")
    (38 "B.Mask" user)
    (39 "F.Mask" user)
    (40 "Dwgs.User" user "User.Drawings")
    (41 "Cmts.User" user "User.Comments")
    (42 "Eco1.User" user "User.Eco1")
    (43 "Eco2.User" user "User.Eco2")
    (44 "Edge.Cuts" user)
    (45 "Margin" user)
    (46 "B.CrtYd" user "B.Courtyard")
    (47 "F.CrtYd" user "F.Courtyard")
    (48 "B.Fab" user)
    (49 "F.Fab" user)
  )
	(footprint "data-center-rdimm-ddr4-tester-footprints:R_0402_1005Metric" (layer "B.Cu")
    (at 192.725 92.675)
    (descr "Resistor SMD 0402")
    (tags "resistor SMD 0402")
    (property "Author" "Antmicro")
    (property "License" "Apache-2.0")
    (property "MPN" "CR0402-FX-1000GLF")
    (property "Manufacturer" "Bourns")
    (property "Sheetfile" "fpga-power.kicad_sch")
    (property "Sheetname" "FPGA power")
    (property "Tolerance" "1%")
    (property "Val" "100R")
    (property "ki_description" "100R resistor in 0402 package with 1% tolerance")
    (attr smd)
    (fp_text reference "R207" (at -0.825 -0.045 45) (layer "B.SilkS")
        (effects (font (size 0.7 0.7) (thickness 0.15)) (justify left bottom mirror))
    )
    (fp_text value "R_100R_0402" (at 0 -1.4 180) (layer "B.Fab") hide
        (effects (font (size 0.7 0.7) (thickness 0.15)) (justify left bottom mirror))
    )
    (fp_text user "License: Apache-2.0" (at -0.95 -5.169 180) (layer "B.Fab") hide
        (effects (font (size 0.7 0.7) (thickness 0.15)) (justify left bottom mirror))
    )
    (fp_text user "Author: Antmicro" (at -0.95 -4.169 180) (layer "B.Fab") hide
        (effects (font (size 0.7 0.7) (thickness 0.15)) (justify left bottom mirror))
    )
    (fp_text user "${REFERENCE}" (at -0.95 -3.168 180) (layer "B.Fab") hide
        (effects (font (size 0.7 0.7) (thickness 0.15)) (justify left bottom mirror))
    )
    (fp_rect (start -0.93 0.47) (end 0.93 -0.47)
      (stroke (width 0.05) (type solid)) (fill none) (layer "B.CrtYd"))
    (fp_rect (start -0.5 0.25) (end 0.5 -0.25)
      (stroke (width 0.15) (type solid)) (fill none) (layer "B.Fab"))
    (pad "1" smd roundrect (at -0.485 0) (size 0.59 0.64) (layers "B.Cu" "B.Paste" "B.Mask") (roundrect_rratio 0.25)
      (net 663 "Net-(U15J-MGTRREF_115)") (pintype "passive"))
    (pad "2" smd roundrect (at 0.485 0) (size 0.59 0.64) (layers "B.Cu" "B.Paste" "B.Mask") (roundrect_rratio 0.25)
      (net 306 "1V2_SYS") (pintype "passive"))
  )
	(footprint "data-center-rdimm-ddr4-tester-footprints:C_0201" (layer "B.Cu")
    (at 174.7 80.075 -90)
    (descr "Capacitor SMD 0201")
    (tags "capacitor SMD 0201")
    (property "Author" "Antmicro")
    (property "Dielectric" "")
    (property "License" "Apache-2.0")
    (property "MPN" "CC0201KRX6S5BB104")
    (property "Manufacturer" "Yaego")
    (property "Sheetfile" "fpga-power.kicad_sch")
    (property "Sheetname" "FPGA power")
    (property "Val" "100n")
    (property "Voltage" "")
    (property "ki_description" " ")
    (attr smd)
    (fp_text reference "C89" (at -1.125 0.4 90) (layer "B.SilkS")
        (effects (font (size 0.7 0.7) (thickness 0.15)) (justify left bottom mirror))
    )
    (fp_text value "C_100n_0201" (at 0 -1.4 90) (layer "B.Fab") hide
        (effects (font (size 0.7 0.7) (thickness 0.15)) (justify left bottom mirror))
    )
    (fp_text user "Author: Antmicro" (at -0.72 -5.4 90) (layer "B.Fab") hide
        (effects (font (size 0.7 0.7) (thickness 0.15)) (justify left bottom mirror))
    )
    (fp_text user "License: Apache-2.0" (at -0.72 -4.4 90) (layer "B.Fab") hide
        (effects (font (size 0.7 0.7) (thickness 0.15)) (justify left bottom mirror))
    )
    (fp_text user "${REFERENCE}" (at -0.72 -3.4 90) (layer "B.Fab") hide
        (effects (font (size 0.7 0.7) (thickness 0.15)) (justify left bottom mirror))
    )
    (fp_rect (start -0.72 0.38) (end 0.72 -0.38)
      (stroke (width 0.05) (type solid)) (fill none) (layer "B.CrtYd"))
    (fp_rect (start 0.3 -0.15) (end -0.301 0.149)
      (stroke (width 0.15) (type solid)) (fill none) (layer "B.Fab"))
    (pad "" smd roundrect (at -0.349 0.002 270) (size 0.318 0.36) (layers "B.Paste") (roundrect_rratio 0.25))
    (pad "" smd roundrect (at 0.341 0.002 270) (size 0.318 0.36) (layers "B.Paste") (roundrect_rratio 0.25))
    (pad "1" smd roundrect (at -0.321 0.002 270) (size 0.46 0.4) (layers "B.Cu" "B.Mask") (roundrect_rratio 0.25)
      (net 143 "3V3_SYS") (pintype "passive"))
    (pad "2" smd roundrect (at 0.32 0.002 270) (size 0.46 0.4) (layers "B.Cu" "B.Mask") (roundrect_rratio 0.25)
      (net 9 "GND") (pintype "passive"))
  )
	(footprint "data-center-rdimm-ddr4-tester-footprints:C_0201" (layer "B.Cu")
    (at 194.2 99.5 180)
    (descr "Capacitor SMD 0201")
    (tags "capacitor SMD 0201")
    (property "Author" "Antmicro")
    (property "Dielectric" "")
    (property "License" "Apache-2.0")
    (property "MPN" "CC0201KRX6S5BB104")
    (property "Manufacturer" "Yaego")
    (property "Sheetfile" "fpga-power.kicad_sch")
    (property "Sheetname" "FPGA power")
    (property "Val" "100n")
    (property "Voltage" "")
    (property "ki_description" " ")
    (attr smd)
    (fp_text reference "C249" (at -3.47 -0.4) (layer "B.SilkS")
        (effects (font (size 0.7 0.7) (thickness 0.15)) (justify left bottom mirror))
    )
    (fp_text value "C_100n_0201" (at 0 -1.4) (layer "B.Fab") hide
        (effects (font (size 0.7 0.7) (thickness 0.15)) (justify left bottom mirror))
    )
    (fp_text user "Author: Antmicro" (at -0.72 -5.4) (layer "B.Fab") hide
        (effects (font (size 0.7 0.7) (thickness 0.15)) (justify left bottom mirror))
    )
    (fp_text user "License: Apache-2.0" (at -0.72 -4.4) (layer "B.Fab") hide
        (effects (font (size 0.7 0.7) (thickness 0.15)) (justify left bottom mirror))
    )
    (fp_text user "${REFERENCE}" (at -0.72 -3.4) (layer "B.Fab") hide
        (effects (font (size 0.7 0.7) (thickness 0.15)) (justify left bottom mirror))
    )
    (fp_rect (start -0.72 0.38) (end 0.72 -0.38)
      (stroke (width 0.05) (type solid)) (fill none) (layer "B.CrtYd"))
    (fp_rect (start 0.3 -0.15) (end -0.301 0.149)
      (stroke (width 0.15) (type solid)) (fill none) (layer "B.Fab"))
    (pad "" smd roundrect (at -0.349 0.002 180) (size 0.318 0.36) (layers "B.Paste") (roundrect_rratio 0.25))
    (pad "" smd roundrect (at 0.341 0.002 180) (size 0.318 0.36) (layers "B.Paste") (roundrect_rratio 0.25))
    (pad "1" smd roundrect (at -0.321 0.002 180) (size 0.46 0.4) (layers "B.Cu" "B.Mask") (roundrect_rratio 0.25)
      (net 306 "1V2_SYS") (pintype "passive"))
    (pad "2" smd roundrect (at 0.32 0.002 180) (size 0.46 0.4) (layers "B.Cu" "B.Mask") (roundrect_rratio 0.25)
      (net 9 "GND") (pintype "passive"))
  )
	(footprint "data-center-rdimm-ddr4-tester-footprints:C_0201" (layer "B.Cu")
    (at 184.4 80.15 -90)
    (descr "Capacitor SMD 0201")
    (tags "capacitor SMD 0201")
    (property "Author" "Antmicro")
    (property "Dielectric" "")
    (property "License" "Apache-2.0")
    (property "MPN" "CC0201KRX6S5BB104")
    (property "Manufacturer" "Yaego")
    (property "Sheetfile" "fpga-power.kicad_sch")
    (property "Sheetname" "FPGA power")
    (property "Val" "100n")
    (property "Voltage" "")
    (property "ki_description" " ")
    (attr smd)
    (fp_text reference "C295" (at -1.12 -1.08 90) (layer "B.SilkS")
        (effects (font (size 0.7 0.7) (thickness 0.15)) (justify left bottom mirror))
    )
    (fp_text value "C_100n_0201" (at 0 -1.4 90) (layer "B.Fab") hide
        (effects (font (size 0.7 0.7) (thickness 0.15)) (justify left bottom mirror))
    )
    (fp_text user "${REFERENCE}" (at -0.72 -3.4 90) (layer "B.Fab") hide
        (effects (font (size 0.7 0.7) (thickness 0.15)) (justify left bottom mirror))
    )
    (fp_text user "License: Apache-2.0" (at -0.72 -4.4 90) (layer "B.Fab") hide
        (effects (font (size 0.7 0.7) (thickness 0.15)) (justify left bottom mirror))
    )
    (fp_text user "Author: Antmicro" (at -0.72 -5.4 90) (layer "B.Fab") hide
        (effects (font (size 0.7 0.7) (thickness 0.15)) (justify left bottom mirror))
    )
    (fp_rect (start -0.72 0.38) (end 0.72 -0.38)
      (stroke (width 0.05) (type solid)) (fill none) (layer "B.CrtYd"))
    (fp_rect (start 0.3 -0.15) (end -0.301 0.149)
      (stroke (width 0.15) (type solid)) (fill none) (layer "B.Fab"))
    (pad "" smd roundrect (at -0.349 0.002 270) (size 0.318 0.36) (layers "B.Paste") (roundrect_rratio 0.25))
    (pad "" smd roundrect (at 0.341 0.002 270) (size 0.318 0.36) (layers "B.Paste") (roundrect_rratio 0.25))
    (pad "1" smd roundrect (at -0.321 0.002 270) (size 0.46 0.4) (layers "B.Cu" "B.Mask") (roundrect_rratio 0.25)
      (net 77 "VDDQ") (pintype "passive"))
    (pad "2" smd roundrect (at 0.32 0.002 270) (size 0.46 0.4) (layers "B.Cu" "B.Mask") (roundrect_rratio 0.25)
      (net 9 "GND") (pintype "passive"))
  )
	(footprint "data-center-rdimm-ddr4-tester-footprints:C_0603_1608Metric" (layer "B.Cu")
    (at 189.725 82.775 90)
    (descr "Capacitor SMD 0603")
    (tags "capacitor 0603")
    (property "Author" "Antmicro")
    (property "Dielectric" "")
    (property "License" "Apache-2.0")
    (property "MPN" "GRM188R60J476ME15D")
    (property "Manufacturer" "Murata")
    (property "Sheetfile" "fpga-power.kicad_sch")
    (property "Sheetname" "FPGA power")
    (property "Val" "47u")
    (property "Voltage" "")
    (property "ki_description" " ")
    (attr smd)
    (fp_text reference "C80" (at 1.085 -0.575 270) (layer "B.SilkS")
        (effects (font (size 0.7 0.7) (thickness 0.15)) (justify left bottom mirror))
    )
    (fp_text value "C_47u_0603" (at 0 -1.6 270) (layer "B.Fab") hide
        (effects (font (size 0.7 0.7) (thickness 0.15)) (justify left bottom mirror))
    )
    (fp_text user "Author: Antmicro" (at -1.682 -4.894 270) (layer "B.Fab") hide
        (effects (font (size 0.7 0.7) (thickness 0.15)) (justify left bottom mirror))
    )
    (fp_text user "${REFERENCE}" (at -1.682 -3.895 270) (layer "B.Fab") hide
        (effects (font (size 0.7 0.7) (thickness 0.15)) (justify left bottom mirror))
    )
    (fp_text user "License: Apache-2.0" (at -1.682 -5.895 270) (layer "B.Fab") hide
        (effects (font (size 0.7 0.7) (thickness 0.15)) (justify left bottom mirror))
    )
    (fp_line (start -0.3 -0.3) (end 0.3 -0.3)
      (stroke (width 0.15) (type solid)) (layer "B.SilkS"))
    (fp_line (start -0.3 0.3) (end 0.3 0.3)
      (stroke (width 0.15) (type solid)) (layer "B.SilkS"))
    (fp_rect (start -1.24 0.7) (end 1.24 -0.7)
      (stroke (width 0.05) (type solid)) (fill none) (layer "B.CrtYd"))
    (fp_rect (start -0.8 0.4) (end 0.8 -0.4)
      (stroke (width 0.15) (type solid)) (fill none) (layer "B.Fab"))
    (pad "1" smd roundrect (at -0.7 0 90) (size 0.6 0.8) (layers "B.Cu" "B.Paste" "B.Mask") (roundrect_rratio 0.2)
      (net 77 "VDDQ") (pintype "passive"))
    (pad "2" smd roundrect (at 0.7 0 90) (size 0.6 0.8) (layers "B.Cu" "B.Paste" "B.Mask") (roundrect_rratio 0.2)
      (net 9 "GND") (pintype "passive"))
  )
	(footprint "data-center-rdimm-ddr4-tester-footprints:R_0402_1005Metric" (layer "B.Cu")
    (at 185.65 129.9 180)
    (descr "Resistor SMD 0402")
    (tags "resistor SMD 0402")
    (property "Author" "Antmicro")
    (property "Current" "1A")
    (property "License" "Apache-2.0")
    (property "MPN" "ERJ2GE0R00X")
    (property "Manufacturer" "Panasonic")
    (property "Sheetfile" "ethernet.kicad_sch")
    (property "Sheetname" "Ethernet")
    (property "Tolerance" "")
    (property "Val" "0R")
    (property "ki_description" "0R resistor in 0402 package with unspecified tolerance")
    (attr smd)
    (fp_text reference "R161" (at -3.72 -0.35) (layer "B.SilkS")
        (effects (font (size 0.7 0.7) (thickness 0.15)) (justify left bottom mirror))
    )
    (fp_text value "R_0R_0402" (at 0 -1.4) (layer "B.Fab") hide
        (effects (font (size 0.7 0.7) (thickness 0.15)) (justify left bottom mirror))
    )
    (fp_text user "License: Apache-2.0" (at -0.95 -5.169) (layer "B.Fab") hide
        (effects (font (size 0.7 0.7) (thickness 0.15)) (justify left bottom mirror))
    )
    (fp_text user "${REFERENCE}" (at -0.95 -3.168) (layer "B.Fab") hide
        (effects (font (size 0.7 0.7) (thickness 0.15)) (justify left bottom mirror))
    )
    (fp_text user "Author: Antmicro" (at -0.95 -4.169) (layer "B.Fab") hide
        (effects (font (size 0.7 0.7) (thickness 0.15)) (justify left bottom mirror))
    )
    (fp_rect (start -0.93 0.47) (end 0.93 -0.47)
      (stroke (width 0.05) (type solid)) (fill none) (layer "B.CrtYd"))
    (fp_rect (start -0.5 0.25) (end 0.5 -0.25)
      (stroke (width 0.15) (type solid)) (fill none) (layer "B.Fab"))
    (pad "1" smd roundrect (at -0.485 0 180) (size 0.59 0.64) (layers "B.Cu" "B.Paste" "B.Mask") (roundrect_rratio 0.25)
      (net 381 "/Ethernet/VSS") (pintype "passive"))
    (pad "2" smd roundrect (at 0.485 0 180) (size 0.59 0.64) (layers "B.Cu" "B.Paste" "B.Mask") (roundrect_rratio 0.25)
      (net 629 "/Ethernet/MPS_DUTY") (pintype "passive"))
  )
	(footprint "data-center-rdimm-ddr4-tester-footprints:C_0201" (layer "B.Cu")
    (at 171.075 97.05 90)
    (descr "Capacitor SMD 0201")
    (tags "capacitor SMD 0201")
    (property "Author" "Antmicro")
    (property "Dielectric" "")
    (property "License" "Apache-2.0")
    (property "MPN" "CC0201KRX6S5BB104")
    (property "Manufacturer" "Yaego")
    (property "Sheetfile" "fpga-power.kicad_sch")
    (property "Sheetname" "FPGA power")
    (property "Val" "100n")
    (property "Voltage" "")
    (property "ki_description" " ")
    (attr smd)
    (fp_text reference "C87" (at 1.11 -0.425 270) (layer "B.SilkS")
        (effects (font (size 0.7 0.7) (thickness 0.15)) (justify left bottom mirror))
    )
    (fp_text value "C_100n_0201" (at 0 -1.4 270) (layer "B.Fab") hide
        (effects (font (size 0.7 0.7) (thickness 0.15)) (justify left bottom mirror))
    )
    (fp_text user "${REFERENCE}" (at -0.72 -3.4 270) (layer "B.Fab") hide
        (effects (font (size 0.7 0.7) (thickness 0.15)) (justify left bottom mirror))
    )
    (fp_text user "License: Apache-2.0" (at -0.72 -4.4 270) (layer "B.Fab") hide
        (effects (font (size 0.7 0.7) (thickness 0.15)) (justify left bottom mirror))
    )
    (fp_text user "Author: Antmicro" (at -0.72 -5.4 270) (layer "B.Fab") hide
        (effects (font (size 0.7 0.7) (thickness 0.15)) (justify left bottom mirror))
    )
    (fp_rect (start -0.72 0.38) (end 0.72 -0.38)
      (stroke (width 0.05) (type solid)) (fill none) (layer "B.CrtYd"))
    (fp_rect (start 0.3 -0.15) (end -0.301 0.149)
      (stroke (width 0.15) (type solid)) (fill none) (layer "B.Fab"))
    (pad "" smd roundrect (at -0.349 0.002 90) (size 0.318 0.36) (layers "B.Paste") (roundrect_rratio 0.25))
    (pad "" smd roundrect (at 0.341 0.002 90) (size 0.318 0.36) (layers "B.Paste") (roundrect_rratio 0.25))
    (pad "1" smd roundrect (at -0.321 0.002 90) (size 0.46 0.4) (layers "B.Cu" "B.Mask") (roundrect_rratio 0.25)
      (net 143 "3V3_SYS") (pintype "passive"))
    (pad "2" smd roundrect (at 0.32 0.002 90) (size 0.46 0.4) (layers "B.Cu" "B.Mask") (roundrect_rratio 0.25)
      (net 9 "GND") (pintype "passive"))
  )
	(footprint "data-center-rdimm-ddr4-tester-footprints:C_0201" (layer "B.Cu")
    (at 174.07 99.27 90)
    (descr "Capacitor SMD 0201")
    (tags "capacitor SMD 0201")
    (property "Author" "Antmicro")
    (property "Dielectric" "")
    (property "License" "Apache-2.0")
    (property "MPN" "CC0201KRX6S5BB104")
    (property "Manufacturer" "Yaego")
    (property "Sheetfile" "fpga-power.kicad_sch")
    (property "Sheetname" "FPGA power")
    (property "Val" "100n")
    (property "Voltage" "")
    (property "ki_description" " ")
    (attr smd)
    (fp_text reference "C302" (at 1.33 1.18 270) (layer "B.SilkS")
        (effects (font (size 0.7 0.7) (thickness 0.15)) (justify left bottom mirror))
    )
    (fp_text value "C_100n_0201" (at 0 -1.4 270) (layer "B.Fab") hide
        (effects (font (size 0.7 0.7) (thickness 0.15)) (justify left bottom mirror))
    )
    (fp_text user "${REFERENCE}" (at -0.72 -3.4 270) (layer "B.Fab") hide
        (effects (font (size 0.7 0.7) (thickness 0.15)) (justify left bottom mirror))
    )
    (fp_text user "Author: Antmicro" (at -0.72 -5.4 270) (layer "B.Fab") hide
        (effects (font (size 0.7 0.7) (thickness 0.15)) (justify left bottom mirror))
    )
    (fp_text user "License: Apache-2.0" (at -0.72 -4.4 270) (layer "B.Fab") hide
        (effects (font (size 0.7 0.7) (thickness 0.15)) (justify left bottom mirror))
    )
    (fp_rect (start -0.72 0.38) (end 0.72 -0.38)
      (stroke (width 0.05) (type solid)) (fill none) (layer "B.CrtYd"))
    (fp_rect (start 0.3 -0.15) (end -0.301 0.149)
      (stroke (width 0.15) (type solid)) (fill none) (layer "B.Fab"))
    (pad "" smd roundrect (at -0.349 0.002 90) (size 0.318 0.36) (layers "B.Paste") (roundrect_rratio 0.25))
    (pad "" smd roundrect (at 0.341 0.002 90) (size 0.318 0.36) (layers "B.Paste") (roundrect_rratio 0.25))
    (pad "1" smd roundrect (at -0.321 0.002 90) (size 0.46 0.4) (layers "B.Cu" "B.Mask") (roundrect_rratio 0.25)
      (net 143 "3V3_SYS") (pintype "passive"))
    (pad "2" smd roundrect (at 0.32 0.002 90) (size 0.46 0.4) (layers "B.Cu" "B.Mask") (roundrect_rratio 0.25)
      (net 9 "GND") (pintype "passive"))
  )
	(footprint "data-center-rdimm-ddr4-tester-footprints:C_0201" (layer "B.Cu")
    (at 192.15 98.65)
    (descr "Capacitor SMD 0201")
    (tags "capacitor SMD 0201")
    (property "Author" "Antmicro")
    (property "Dielectric" "")
    (property "License" "Apache-2.0")
    (property "MPN" "CC0201KRX6S5BB104")
    (property "Manufacturer" "Yaego")
    (property "Sheetfile" "fpga-power.kicad_sch")
    (property "Sheetname" "FPGA power")
    (property "Val" "100n")
    (property "Voltage" "")
    (property "ki_description" " ")
    (attr smd)
    (fp_text reference "C242" (at 3.48 0.22 180) (layer "B.SilkS")
        (effects (font (size 0.7 0.7) (thickness 0.15)) (justify left bottom mirror))
    )
    (fp_text value "C_100n_0201" (at 0 -1.4 180) (layer "B.Fab") hide
        (effects (font (size 0.7 0.7) (thickness 0.15)) (justify left bottom mirror))
    )
    (fp_text user "${REFERENCE}" (at -0.72 -3.4 180) (layer "B.Fab") hide
        (effects (font (size 0.7 0.7) (thickness 0.15)) (justify left bottom mirror))
    )
    (fp_text user "Author: Antmicro" (at -0.72 -5.4 180) (layer "B.Fab") hide
        (effects (font (size 0.7 0.7) (thickness 0.15)) (justify left bottom mirror))
    )
    (fp_text user "License: Apache-2.0" (at -0.72 -4.4 180) (layer "B.Fab") hide
        (effects (font (size 0.7 0.7) (thickness 0.15)) (justify left bottom mirror))
    )
    (fp_rect (start -0.72 0.38) (end 0.72 -0.38)
      (stroke (width 0.05) (type solid)) (fill none) (layer "B.CrtYd"))
    (fp_rect (start 0.3 -0.15) (end -0.301 0.149)
      (stroke (width 0.15) (type solid)) (fill none) (layer "B.Fab"))
    (pad "" smd roundrect (at -0.349 0.002) (size 0.318 0.36) (layers "B.Paste") (roundrect_rratio 0.25))
    (pad "" smd roundrect (at 0.341 0.002) (size 0.318 0.36) (layers "B.Paste") (roundrect_rratio 0.25))
    (pad "1" smd roundrect (at -0.321 0.002) (size 0.46 0.4) (layers "B.Cu" "B.Mask") (roundrect_rratio 0.25)
      (net 147 "1V0_SYS") (pintype "passive"))
    (pad "2" smd roundrect (at 0.32 0.002) (size 0.46 0.4) (layers "B.Cu" "B.Mask") (roundrect_rratio 0.25)
      (net 9 "GND") (pintype "passive"))
  )
)
